FILE_TYPE = CONNECTIVITY;
{Allegro Design Entry HDL 17.4-2019 S026 (4007227) 1/17/2022}
"PAGE_NUMBER" = 425;
0"NC";
END.
